# TIMECARD (Time Appliance Project (Time Card)) — schematic netlist excerpt (pin names and nets, part order shuffled) for the footprints in the layout excerpt that follows; sources: Cadence DE-HDL packaged netlist, KiCad conversion of R4006-B0001-02_R01.brd

C266  CAPACITOR  1000PF 50V 5%  pkg SMC_0402R_H022  page 29 : \1\ = XP1R0V_SW ; \2\ = UNNAMED_523_CAPACITOR_I31_2
R256  RESISTOR  1KOHM 1%  pkg SMC_0402R_H016  page 26 : \1\ = UNNAMED_14_OPTICAL_I143_A ; \2\ = UNNAMED_14_RESISTOR_I65_2

(kicad_pcb
	(version 20260206)
	(generator "pcbnew")
	(generator_version "10.0")
	(general
		(thickness 1.6)
		(legacy_teardrops no)
	)
	(paper "A4")
	(title_block
		(title "timecard-production-celestica-r4006 — R4006-B0001-02_R01.brd")
		(comment 1 "Time Appliance Project (Time Card) / footprints 815-816 of 1113")
	)
	(layers
		(0 "F.Cu" signal "TOP")
		(4 "In1.Cu" signal "L02_GND1")
		(6 "In2.Cu" signal "L03_SIG1")
		(8 "In3.Cu" signal "L04_GND2")
		(10 "In4.Cu" signal "L05_VCC1")
		(12 "In5.Cu" signal "L06_VCC2")
		(14 "In6.Cu" signal "L07_GND3")
		(16 "In7.Cu" signal "L08_SIG2")
		(18 "In8.Cu" signal "L09_GND4")
		(2 "B.Cu" signal "BOTTOM")
		(9 "F.Adhes" user "F.Adhesive")
		(11 "B.Adhes" user "B.Adhesive")
		(13 "F.Paste" user "Package Geometry/Pastemask Top")
		(15 "B.Paste" user "Package Geometry/Pastemask Bottom")
		(5 "F.SilkS" user "Ref Des/Silkscreen Top")
		(7 "B.SilkS" user "Ref Des/Silkscreen Bottom")
		(1 "F.Mask" user "Board Geometry/Soldermask Top")
		(3 "B.Mask" user "Board Geometry/Soldermask Bottom")
		(17 "Dwgs.User" user "User.Drawings")
		(19 "Cmts.User" user "User.Comments")
		(21 "Eco1.User" user "User.Eco1")
		(23 "Eco2.User" user "User.Eco2")
		(25 "Edge.Cuts" user "Board Geometry/Outline")
		(27 "Margin" user)
		(31 "F.CrtYd" user "Package Geometry/Place Bound Top")
		(29 "B.CrtYd" user "Package Geometry/Place Bound Bottom")
		(35 "F.Fab" user "Ref Des/Assembly Top")
		(33 "B.Fab" user "Ref Des/Assembly Bottom")
	)
	(footprint ""
		(layer "B.Cu")
		(at 147.066 -104.648 180)
		(property "Reference" "R256"
			(at -1.016 -3.21437 0)
			(unlocked yes)
			(layer "B.SilkS")
			(effects
				(font
					(size 0.7874 0.5842)
					(thickness 0.1524)
				)
				(justify mirror)
			)
		)
		(property "Value" "VAL*"
			(at -0.02032 2.13233 180)
			(unlocked yes)
			(layer "B.Fab")
			(hide yes)
			(effects
				(font
					(size 0.7874 0.5842)
					(thickness 0.1524)
				)
				(justify mirror)
			)
		)
		(property "Tolerance" "TOL*"
			(at -0.044704 3.05435 180)
			(unlocked yes)
			(layer "Cmts.User")
			(hide yes)
			(effects
				(font
					(size 0.7874 0.5842)
					(thickness 0.1524)
				)
				(justify mirror)
			)
		)
		(property "User Part Number" "PARTNUM*"
			(at -0.02032 4.024884 180)
			(unlocked yes)
			(layer "Cmts.User")
			(hide yes)
			(effects
				(font
					(size 0.7874 0.5842)
					(thickness 0.1524)
				)
				(justify mirror)
			)
		)
		(property "Device Type" "RESISTOR-G155-11001-01,1KOHM,1%"
			(at -0.008382 1.210564 180)
			(unlocked yes)
			(layer "B.Fab")
			(hide yes)
			(effects
				(font
					(size 0.7874 0.5842)
					(thickness 0.1524)
				)
				(justify mirror)
			)
		)
		(duplicate_pad_numbers_are_jumpers no)
		(fp_line
			(start 1.143 0.5588)
			(end -1.143 0.5588)
			(stroke
				(width 0.1)
				(type default)
			)
			(layer "B.SilkS")
		)
		(fp_line
			(start 1.143 -0.5588)
			(end 1.143 0.5588)
			(stroke
				(width 0.1)
				(type default)
			)
			(layer "B.SilkS")
		)
		(fp_line
			(start -1.143 0.5588)
			(end -1.143 -0.5588)
			(stroke
				(width 0.1)
				(type default)
			)
			(layer "B.SilkS")
		)
		(fp_line
			(start -1.143 -0.5588)
			(end 1.143 -0.5588)
			(stroke
				(width 0.1)
				(type default)
			)
			(layer "B.SilkS")
		)
		(fp_rect
			(start -1.143 -0.5588)
			(end 1.143 0.5588)
			(stroke
				(width 0)
				(type default)
			)
			(fill no)
			(layer "B.CrtYd")
		)
		(fp_line
			(start 0.508 0.3048)
			(end -0.508 0.3048)
			(stroke
				(width 0.1)
				(type default)
			)
			(layer "B.Fab")
		)
		(fp_line
			(start 0.508 -0.3048)
			(end 0.508 0.3048)
			(stroke
				(width 0.1)
				(type default)
			)
			(layer "B.Fab")
		)
		(fp_line
			(start -0.508 0.3048)
			(end -0.508 -0.3048)
			(stroke
				(width 0.1)
				(type default)
			)
			(layer "B.Fab")
		)
		(fp_line
			(start -0.508 -0.3048)
			(end 0.508 -0.3048)
			(stroke
				(width 0.1)
				(type default)
			)
			(layer "B.Fab")
		)
		(pad "1" smd rect
			(at 0.5334 0)
			(size 0.7112 0.6096)
			(layers "B.Cu" "B.Mask" "B.Paste")
			(net "UNNAMED_14_OPTICAL_I143_A")
		)
		(pad "2" smd rect
			(at -0.5334 0)
			(size 0.7112 0.6096)
			(layers "B.Cu" "B.Mask" "B.Paste")
			(net "UNNAMED_14_RESISTOR_I65_2")
		)
		(zone
			(layer "B.Cu")
			(hatch none 0.5)
			(connect_pads
				(clearance 0)
			)
			(min_thickness 0.25)
			(keepout
				(tracks allowed)
				(vias not_allowed)
				(pads allowed)
				(copperpour not_allowed)
				(footprints allowed)
			)
			(placement
				(enabled no)
				(sheetname "")
			)
			(fill
				(thermal_gap 0.5)
				(thermal_bridge_width 0.5)
				(island_removal_mode 0)
			)
			(polygon
				(pts
					(xy 147.1422 -104.3432) (xy 147.1422 -104.9528) (xy 146.9898 -104.9528) (xy 146.9898 -104.3432)
				)
			)
		)
	)
	(footprint ""
		(layer "B.Cu")
		(at 142.494 -50.292 180)
		(property "Reference" "C266"
			(at 0.254 -1.56337 0)
			(unlocked yes)
			(layer "B.SilkS")
			(effects
				(font
					(size 0.7874 0.5842)
					(thickness 0.1524)
				)
				(justify mirror)
			)
		)
		(property "Value" "VAL*"
			(at -0.0762 2.067306 180)
			(unlocked yes)
			(layer "B.Fab")
			(hide yes)
			(effects
				(font
					(size 0.7874 0.5842)
					(thickness 0.1524)
				)
				(justify mirror)
			)
		)
		(property "Device Type" "CAPACITOR-G105-0A102-FJ,1000PFA"
			(at -0.0508 1.127506 180)
			(unlocked yes)
			(layer "B.Fab")
			(hide yes)
			(effects
				(font
					(size 0.7874 0.5842)
					(thickness 0.1524)
				)
				(justify mirror)
			)
		)
		(property "User Part Number" "PARTNUM*"
			(at -0.1016 4.023106 180)
			(unlocked yes)
			(layer "Cmts.User")
			(hide yes)
			(effects
				(font
					(size 0.7874 0.5842)
					(thickness 0.1524)
				)
				(justify mirror)
			)
		)
		(property "Tolerance" "TOL*"
			(at -0.0762 3.032506 180)
			(unlocked yes)
			(layer "Cmts.User")
			(hide yes)
			(effects
				(font
					(size 0.7874 0.5842)
					(thickness 0.1524)
				)
				(justify mirror)
			)
		)
		(duplicate_pad_numbers_are_jumpers no)
		(fp_line
			(start 1.143 0.5588)
			(end -1.143 0.5588)
			(stroke
				(width 0.1)
				(type default)
			)
			(layer "B.SilkS")
		)
		(fp_line
			(start 1.143 -0.5588)
			(end 1.143 0.5588)
			(stroke
				(width 0.1)
				(type default)
			)
			(layer "B.SilkS")
		)
		(fp_line
			(start -1.143 0.5588)
			(end -1.143 -0.5588)
			(stroke
				(width 0.1)
				(type default)
			)
			(layer "B.SilkS")
		)
		(fp_line
			(start -1.143 -0.5588)
			(end 1.143 -0.5588)
			(stroke
				(width 0.1)
				(type default)
			)
			(layer "B.SilkS")
		)
		(fp_rect
			(start -1.143 0.5588)
			(end 1.143 -0.5588)
			(stroke
				(width 0)
				(type default)
			)
			(fill no)
			(layer "B.CrtYd")
		)
		(fp_line
			(start 0.508 0.3048)
			(end -0.508 0.3048)
			(stroke
				(width 0.1)
				(type default)
			)
			(layer "B.Fab")
		)
		(fp_line
			(start 0.508 -0.3048)
			(end 0.508 0.3048)
			(stroke
				(width 0.1)
				(type default)
			)
			(layer "B.Fab")
		)
		(fp_line
			(start -0.508 0.3048)
			(end -0.508 -0.3048)
			(stroke
				(width 0.1)
				(type default)
			)
			(layer "B.Fab")
		)
		(fp_line
			(start -0.508 -0.3048)
			(end 0.508 -0.3048)
			(stroke
				(width 0.1)
				(type default)
			)
			(layer "B.Fab")
		)
		(pad "1" smd rect
			(at 0.5334 0)
			(size 0.7112 0.6096)
			(layers "B.Cu" "B.Mask" "B.Paste")
			(net "XP1R0V_SW")
		)
		(pad "2" smd rect
			(at -0.5334 0)
			(size 0.7112 0.6096)
			(layers "B.Cu" "B.Mask" "B.Paste")
			(net "UNNAMED_523_CAPACITOR_I31_2")
		)
		(zone
			(layer "B.Cu")
			(hatch none 0.5)
			(connect_pads
				(clearance 0)
			)
			(min_thickness 0.25)
			(keepout
				(tracks allowed)
				(vias not_allowed)
				(pads allowed)
				(copperpour not_allowed)
				(footprints allowed)
			)
			(placement
				(enabled no)
				(sheetname "")
			)
			(fill
				(thermal_gap 0.5)
				(thermal_bridge_width 0.5)
				(island_removal_mode 0)
			)
			(polygon
				(pts
					(xy 142.5702 -50.5968) (xy 142.4178 -50.5968) (xy 142.4178 -49.9872) (xy 142.5702 -49.9872)
				)
			)
		)
	)
)
